(kicad_pcb
	(version 20260206)
	(generator "pcbnew")
	(generator_version "10.0")
	(general
		(thickness 1.6)
		(legacy_teardrops no)
	)
	(paper "A4")
	(title_block
		(title "Bryce Canyon_F.DPB_16315-1-OCP.brd")
		(comment 1 "Bryce Canyon / footprints 1845-1851 of 2223")
	)
	(layers
		(0 "F.Cu" signal "TOP")
		(4 "In1.Cu" signal "L2GND")
		(6 "In2.Cu" signal "L3")
		(8 "In3.Cu" signal "L4GND")
		(10 "In4.Cu" signal "L5")
		(12 "In5.Cu" signal "L6VCC")
		(14 "In6.Cu" signal "L7VCC")
		(16 "In7.Cu" signal "L8")
		(18 "In8.Cu" signal "L9GND")
		(20 "In9.Cu" signal "L10")
		(22 "In10.Cu" signal "L11GND")
		(2 "B.Cu" signal "BOTTOM")
		(9 "F.Adhes" user "F.Adhesive")
		(11 "B.Adhes" user "B.Adhesive")
		(13 "F.Paste" user "Package Geometry/Pastemask Top")
		(15 "B.Paste" user "Package Geometry/Pastemask Bottom")
		(5 "F.SilkS" user "Ref Des/Silkscreen Top")
		(7 "B.SilkS" user "Ref Des/Silkscreen Bottom")
		(1 "F.Mask" user "Board Geometry/Soldermask Top")
		(3 "B.Mask" user "Board Geometry/Soldermask Bottom")
		(17 "Dwgs.User" user "User.Drawings")
		(19 "Cmts.User" user "User.Comments")
		(21 "Eco1.User" user "User.Eco1")
		(23 "Eco2.User" user "User.Eco2")
		(25 "Edge.Cuts" user "Board Geometry/Outline")
		(27 "Margin" user)
		(31 "F.CrtYd" user "Package Geometry/Place Bound Top")
		(29 "B.CrtYd" user "Package Geometry/Place Bound Bottom")
		(35 "F.Fab" user "Ref Des/Assembly Top")
		(33 "B.Fab" user "Ref Des/Assembly Bottom")
	)
	(footprint ""
		(layer "F.Cu")
		(at 335.29397 -18.650966 180)
		(property "Reference" "C19"
			(at 0 0 180)
			(layer "F.SilkS")
			(hide yes)
			(effects
				(font
					(size 1.27 1.27)
				)
			)
		)
		(property "Value" "SCD1U16V2KX-3GP"
			(at 1.1811 -2.7051 180)
			(unlocked yes)
			(layer "F.Fab")
			(hide yes)
			(effects
				(font
					(size 1.016 1.016)
					(thickness 0.1524)
				)
			)
		)
		(property "Device Type" "C402H22"
			(at 1.1811 -4.2291 180)
			(unlocked yes)
			(layer "F.Fab")
			(hide yes)
			(effects
				(font
					(size 1.016 1.016)
					(thickness 0.1524)
				)
			)
		)
		(duplicate_pad_numbers_are_jumpers no)
		(fp_rect
			(start -0.4318 0.9525)
			(end 0.4318 -0.9525)
			(stroke
				(width 0)
				(type default)
			)
			(fill no)
			(layer "F.CrtYd")
		)
		(fp_rect
			(start -0.4318 0.9525)
			(end 0.4318 -0.9525)
			(stroke
				(width 0)
				(type default)
			)
			(fill no)
			(layer "F.Fab")
		)
		(pad "1" smd custom
			(at 0 -0.4445 180)
			(size 0.1524 0.1524)
			(layers "F.Cu" "F.Mask" "F.Paste")
			(net "P3V3_STBY_B")
			(options
				(clearance outline)
				(anchor circle)
			)
			(primitives
				(gr_poly
					(pts
						(arc
							(start 0.3048 -0.2032)
							(mid 0.275042 -0.275042)
							(end 0.2032 -0.3048)
						)
						(arc
							(start -0.2032 -0.3048)
							(mid -0.275042 -0.275042)
							(end -0.3048 -0.2032)
						)
						(arc
							(start -0.3048 0.2032)
							(mid -0.275042 0.275042)
							(end -0.2032 0.3048)
						)
						(arc
							(start 0.2032 0.3048)
							(mid 0.275042 0.275042)
							(end 0.3048 0.2032)
						)
					)
					(width 0)
					(fill yes)
				)
			)
		)
		(pad "2" smd custom
			(at 0 0.4445 180)
			(size 0.1524 0.1524)
			(layers "F.Cu" "F.Mask" "F.Paste")
			(net "GND")
			(options
				(clearance outline)
				(anchor circle)
			)
			(primitives
				(gr_poly
					(pts
						(arc
							(start 0.3048 -0.2032)
							(mid 0.275042 -0.275042)
							(end 0.2032 -0.3048)
						)
						(arc
							(start -0.2032 -0.3048)
							(mid -0.275042 -0.275042)
							(end -0.3048 -0.2032)
						)
						(arc
							(start -0.3048 0.2032)
							(mid -0.275042 0.275042)
							(end -0.2032 0.3048)
						)
						(arc
							(start 0.2032 0.3048)
							(mid 0.275042 0.275042)
							(end 0.3048 0.2032)
						)
					)
					(width 0)
					(fill yes)
				)
			)
		)
	)
	(footprint ""
		(layer "F.Cu")
		(at 242.522502 -379.837696 -90)
		(property "Reference" "C596"
			(at 0 0 270)
			(layer "F.SilkS")
			(hide yes)
			(effects
				(font
					(size 1.27 1.27)
				)
			)
		)
		(property "Value" "SCD033U50V3KX-1GP"
			(at 0 -2.8194 270)
			(unlocked yes)
			(layer "F.Fab")
			(hide yes)
			(effects
				(font
					(size 1.016 1.016)
					(thickness 0.1524)
				)
			)
		)
		(property "Device Type" "C603H36"
			(at 0 -4.3434 270)
			(unlocked yes)
			(layer "F.Fab")
			(hide yes)
			(effects
				(font
					(size 1.016 1.016)
					(thickness 0.1524)
				)
			)
		)
		(duplicate_pad_numbers_are_jumpers no)
		(fp_line
			(start 0.508 0)
			(end -0.508 0)
			(stroke
				(width 0.2032)
				(type default)
			)
			(layer "F.SilkS")
		)
		(fp_rect
			(start -0.5842 1.3335)
			(end 0.5842 -1.3335)
			(stroke
				(width 0)
				(type default)
			)
			(fill no)
			(layer "F.CrtYd")
		)
		(fp_rect
			(start -0.5842 1.3335)
			(end 0.5842 -1.3335)
			(stroke
				(width 0)
				(type default)
			)
			(fill no)
			(layer "F.Fab")
		)
		(pad "1" smd custom
			(at 0 -0.762 270)
			(size 0.2159 0.2159)
			(layers "F.Cu" "F.Mask" "F.Paste")
			(net "MB3_CM_GATE_C")
			(options
				(clearance outline)
				(anchor circle)
			)
			(primitives
				(gr_poly
					(pts
						(arc
							(start -0.3302 -0.4318)
							(mid -0.402042 -0.402042)
							(end -0.4318 -0.3302)
						)
						(arc
							(start -0.4318 0.3302)
							(mid -0.402042 0.402042)
							(end -0.3302 0.4318)
						)
						(arc
							(start 0.3302 0.4318)
							(mid 0.402042 0.402042)
							(end 0.4318 0.3302)
						)
						(arc
							(start 0.4318 -0.3302)
							(mid 0.402042 -0.402042)
							(end 0.3302 -0.4318)
						)
					)
					(width 0)
					(fill yes)
				)
			)
		)
		(pad "2" smd custom
			(at 0 0.762 270)
			(size 0.2159 0.2159)
			(layers "F.Cu" "F.Mask" "F.Paste")
			(net "GND")
			(options
				(clearance outline)
				(anchor circle)
			)
			(primitives
				(gr_poly
					(pts
						(arc
							(start -0.3302 -0.4318)
							(mid -0.402042 -0.402042)
							(end -0.4318 -0.3302)
						)
						(arc
							(start -0.4318 0.3302)
							(mid -0.402042 0.402042)
							(end -0.3302 0.4318)
						)
						(arc
							(start 0.3302 0.4318)
							(mid 0.402042 0.402042)
							(end 0.4318 0.3302)
						)
						(arc
							(start 0.4318 -0.3302)
							(mid 0.402042 -0.402042)
							(end 0.3302 -0.4318)
						)
					)
					(width 0)
					(fill yes)
				)
			)
		)
	)
	(footprint ""
		(layer "F.Cu")
		(at 233.4514 -231.3178)
		(property "Reference" "R72"
			(at 0 0 0)
			(layer "F.SilkS")
			(hide yes)
			(effects
				(font
					(size 1.27 1.27)
				)
			)
		)
		(property "Value" "4K7R2F-GP"
			(at 0.064008 -3.993896 0)
			(unlocked yes)
			(layer "F.Fab")
			(hide yes)
			(effects
				(font
					(size 1.016 1.016)
					(thickness 0.1524)
				)
			)
		)
		(property "Device Type" "R402H16"
			(at 0.064008 -5.517896 0)
			(unlocked yes)
			(layer "F.Fab")
			(hide yes)
			(effects
				(font
					(size 1.016 1.016)
					(thickness 0.1524)
				)
			)
		)
		(duplicate_pad_numbers_are_jumpers no)
		(fp_line
			(start -0.508 -0.9398)
			(end -0.508 0.9398)
			(stroke
				(width 0.1524)
				(type default)
			)
			(layer "F.SilkS")
		)
		(fp_line
			(start 0.508 -0.9398)
			(end -0.508 -0.9398)
			(stroke
				(width 0.1524)
				(type default)
			)
			(layer "F.SilkS")
		)
		(fp_rect
			(start -0.508 0.9398)
			(end 0.508 -0.9398)
			(stroke
				(width 0)
				(type default)
			)
			(fill no)
			(layer "F.CrtYd")
		)
		(fp_rect
			(start -0.508 0.9398)
			(end 0.508 -0.9398)
			(stroke
				(width 0)
				(type default)
			)
			(fill no)
			(layer "F.Fab")
		)
		(pad "1" smd custom
			(at 0 -0.4445)
			(size 0.1397 0.1397)
			(layers "F.Cu" "F.Mask" "F.Paste")
			(net "IO_EXP1_A0")
			(options
				(clearance outline)
				(anchor circle)
			)
			(primitives
				(gr_poly
					(pts
						(arc
							(start -0.1778 -0.2794)
							(mid -0.249642 -0.249642)
							(end -0.2794 -0.1778)
						)
						(arc
							(start -0.2794 0.1778)
							(mid -0.249642 0.249642)
							(end -0.1778 0.2794)
						)
						(arc
							(start 0.1778 0.2794)
							(mid 0.249642 0.249642)
							(end 0.2794 0.1778)
						)
						(arc
							(start 0.2794 -0.1778)
							(mid 0.249642 -0.249642)
							(end 0.1778 -0.2794)
						)
					)
					(width 0)
					(fill yes)
				)
			)
		)
		(pad "2" smd custom
			(at 0 0.4445)
			(size 0.1397 0.1397)
			(layers "F.Cu" "F.Mask" "F.Paste")
			(net "GND")
			(options
				(clearance outline)
				(anchor circle)
			)
			(primitives
				(gr_poly
					(pts
						(arc
							(start -0.1778 -0.2794)
							(mid -0.249642 -0.249642)
							(end -0.2794 -0.1778)
						)
						(arc
							(start -0.2794 0.1778)
							(mid -0.249642 0.249642)
							(end -0.1778 0.2794)
						)
						(arc
							(start 0.1778 0.2794)
							(mid 0.249642 0.249642)
							(end 0.2794 0.1778)
						)
						(arc
							(start 0.2794 -0.1778)
							(mid 0.249642 -0.249642)
							(end 0.1778 -0.2794)
						)
					)
					(width 0)
					(fill yes)
				)
			)
		)
	)
	(footprint ""
		(layer "F.Cu")
		(at 238.506 -394.3858 -90)
		(property "Reference" "R1164"
			(at 0 0 270)
			(layer "F.SilkS")
			(hide yes)
			(effects
				(font
					(size 1.27 1.27)
				)
			)
		)
		(property "Value" "100KR2F-L1-GP"
			(at 0.064008 -3.993896 270)
			(unlocked yes)
			(layer "F.Fab")
			(hide yes)
			(effects
				(font
					(size 1.016 1.016)
					(thickness 0.1524)
				)
			)
		)
		(property "Device Type" "R402H16"
			(at 0.064008 -5.517896 270)
			(unlocked yes)
			(layer "F.Fab")
			(hide yes)
			(effects
				(font
					(size 1.016 1.016)
					(thickness 0.1524)
				)
			)
		)
		(duplicate_pad_numbers_are_jumpers no)
		(fp_line
			(start -0.508 -0.9398)
			(end -0.508 0.9398)
			(stroke
				(width 0.1524)
				(type default)
			)
			(layer "F.SilkS")
		)
		(fp_line
			(start 0.508 -0.9398)
			(end -0.508 -0.9398)
			(stroke
				(width 0.1524)
				(type default)
			)
			(layer "F.SilkS")
		)
		(fp_rect
			(start -0.508 0.9398)
			(end 0.508 -0.9398)
			(stroke
				(width 0)
				(type default)
			)
			(fill no)
			(layer "F.CrtYd")
		)
		(fp_rect
			(start -0.508 0.9398)
			(end 0.508 -0.9398)
			(stroke
				(width 0)
				(type default)
			)
			(fill no)
			(layer "F.Fab")
		)
		(pad "1" smd custom
			(at 0 -0.4445 270)
			(size 0.1397 0.1397)
			(layers "F.Cu" "F.Mask" "F.Paste")
			(net "MB3_VCAP_R")
			(options
				(clearance outline)
				(anchor circle)
			)
			(primitives
				(gr_poly
					(pts
						(arc
							(start -0.1778 -0.2794)
							(mid -0.249642 -0.249642)
							(end -0.2794 -0.1778)
						)
						(arc
							(start -0.2794 0.1778)
							(mid -0.249642 0.249642)
							(end -0.1778 0.2794)
						)
						(arc
							(start 0.1778 0.2794)
							(mid 0.249642 0.249642)
							(end 0.2794 0.1778)
						)
						(arc
							(start 0.2794 -0.1778)
							(mid 0.249642 -0.249642)
							(end 0.1778 -0.2794)
						)
					)
					(width 0)
					(fill yes)
				)
			)
		)
		(pad "2" smd custom
			(at 0 0.4445 270)
			(size 0.1397 0.1397)
			(layers "F.Cu" "F.Mask" "F.Paste")
			(net "MB3_ISTART_R")
			(options
				(clearance outline)
				(anchor circle)
			)
			(primitives
				(gr_poly
					(pts
						(arc
							(start -0.1778 -0.2794)
							(mid -0.249642 -0.249642)
							(end -0.2794 -0.1778)
						)
						(arc
							(start -0.2794 0.1778)
							(mid -0.249642 0.249642)
							(end -0.1778 0.2794)
						)
						(arc
							(start 0.1778 0.2794)
							(mid 0.249642 0.249642)
							(end 0.2794 0.1778)
						)
						(arc
							(start 0.2794 -0.1778)
							(mid 0.249642 -0.249642)
							(end 0.1778 -0.2794)
						)
					)
					(width 0)
					(fill yes)
				)
			)
		)
	)
	(footprint ""
		(layer "F.Cu")
		(at 112.450118 -94.400116)
		(property "Reference" "FLED16"
			(at 0 0 0)
			(layer "F.SilkS")
			(hide yes)
			(effects
				(font
					(size 1.27 1.27)
				)
			)
		)
		(property "Value" "LED-BY-19-GP"
			(at -2.132076 1.414018 0)
			(unlocked yes)
			(layer "F.Fab")
			(hide yes)
			(effects
				(font
					(size 1.016 1.016)
					(thickness 0.1524)
				)
			)
		)
		(property "Device Type" "LED-1615-4PH26"
			(at -2.132076 -0.109982 0)
			(unlocked yes)
			(layer "F.Fab")
			(hide yes)
			(effects
				(font
					(size 1.016 1.016)
					(thickness 0.1524)
				)
			)
		)
		(duplicate_pad_numbers_are_jumpers no)
		(fp_line
			(start -1.2954 0.254)
			(end -1.2954 1.6002)
			(stroke
				(width 0.508)
				(type default)
			)
			(layer "F.SilkS")
		)
		(fp_line
			(start -1.2954 1.6002)
			(end 1.2954 1.6002)
			(stroke
				(width 0.508)
				(type default)
			)
			(layer "F.SilkS")
		)
		(fp_line
			(start -1.1176 -1.4224)
			(end 1.1176 -1.4224)
			(stroke
				(width 0.1524)
				(type default)
			)
			(layer "F.SilkS")
		)
		(fp_line
			(start -1.1176 1.4224)
			(end -1.1176 -1.4224)
			(stroke
				(width 0.1524)
				(type default)
			)
			(layer "F.SilkS")
		)
		(fp_line
			(start 1.1176 -1.4224)
			(end 1.1176 1.4224)
			(stroke
				(width 0.1524)
				(type default)
			)
			(layer "F.SilkS")
		)
		(fp_line
			(start 1.1176 1.4224)
			(end -1.1176 1.4224)
			(stroke
				(width 0.1524)
				(type default)
			)
			(layer "F.SilkS")
		)
		(fp_line
			(start 1.2954 1.6002)
			(end 1.2954 0.254)
			(stroke
				(width 0.508)
				(type default)
			)
			(layer "F.SilkS")
		)
		(fp_rect
			(start -0.7493 0.8001)
			(end 0.7493 -0.8001)
			(stroke
				(width 0)
				(type default)
			)
			(fill no)
			(layer "F.CrtYd")
		)
		(fp_poly
			(pts
				(xy -1.3716 1.6764) (xy -1.3716 -1.6764) (xy 1.3716 -1.6764) (xy 1.3716 0.0635) (xy 0.7493 0.0635)
				(xy 0.7493 -0.8001) (xy -0.7493 -0.8001) (xy -0.7493 0.8001) (xy 0.7493 0.8001) (xy 0.7493 0.0762)
				(xy 1.3716 0.0762) (xy 1.3716 1.6764)
			)
			(stroke
				(width 0)
				(type default)
			)
			(fill no)
			(layer "F.CrtYd")
		)
		(fp_rect
			(start -1.3716 1.6764)
			(end 1.3716 -1.6764)
			(stroke
				(width 0)
				(type default)
			)
			(fill no)
			(layer "F.Fab")
		)
		(pad "1" smd rect
			(at 0.50038 -0.73025)
			(size 0.7112 0.8636)
			(layers "F.Cu" "F.Mask" "F.Paste")
			(net "DRV_ACT_15")
		)
		(pad "2" smd rect
			(at -0.50038 -0.73025)
			(size 0.7112 0.8636)
			(layers "F.Cu" "F.Mask" "F.Paste")
			(net "FLT_HDD15")
		)
		(pad "3" smd rect
			(at 0.50038 0.73025)
			(size 0.7112 0.8636)
			(layers "F.Cu" "F.Mask" "F.Paste")
			(net "DRV_ACT_15_N")
		)
		(pad "4" smd rect
			(at -0.50038 0.73025)
			(size 0.7112 0.8636)
			(layers "F.Cu" "F.Mask" "F.Paste")
			(net "FLT_HDD15_N")
		)
	)
	(footprint ""
		(layer "F.Cu")
		(at 426.755052 -42.585894)
		(property "Reference" "R901"
			(at 0 0 0)
			(layer "F.SilkS")
			(hide yes)
			(effects
				(font
					(size 1.27 1.27)
				)
			)
		)
		(property "Value" "4K7R2J-2-GP"
			(at 0.064008 -3.993896 0)
			(unlocked yes)
			(layer "F.Fab")
			(hide yes)
			(effects
				(font
					(size 1.016 1.016)
					(thickness 0.1524)
				)
			)
		)
		(property "Device Type" "R402H16"
			(at 0.064008 -5.517896 0)
			(unlocked yes)
			(layer "F.Fab")
			(hide yes)
			(effects
				(font
					(size 1.016 1.016)
					(thickness 0.1524)
				)
			)
		)
		(duplicate_pad_numbers_are_jumpers no)
		(fp_line
			(start -0.508 -0.9398)
			(end -0.508 0.9398)
			(stroke
				(width 0.1524)
				(type default)
			)
			(layer "F.SilkS")
		)
		(fp_line
			(start 0.508 -0.9398)
			(end -0.508 -0.9398)
			(stroke
				(width 0.1524)
				(type default)
			)
			(layer "F.SilkS")
		)
		(fp_rect
			(start -0.508 0.9398)
			(end 0.508 -0.9398)
			(stroke
				(width 0)
				(type default)
			)
			(fill no)
			(layer "F.CrtYd")
		)
		(fp_rect
			(start -0.508 0.9398)
			(end 0.508 -0.9398)
			(stroke
				(width 0)
				(type default)
			)
			(fill no)
			(layer "F.Fab")
		)
		(pad "1" smd custom
			(at 0 -0.4445)
			(size 0.1397 0.1397)
			(layers "F.Cu" "F.Mask" "F.Paste")
			(net "SW_PWR_R_HDD33")
			(options
				(clearance outline)
				(anchor circle)
			)
			(primitives
				(gr_poly
					(pts
						(arc
							(start -0.1778 -0.2794)
							(mid -0.249642 -0.249642)
							(end -0.2794 -0.1778)
						)
						(arc
							(start -0.2794 0.1778)
							(mid -0.249642 0.249642)
							(end -0.1778 0.2794)
						)
						(arc
							(start 0.1778 0.2794)
							(mid 0.249642 0.249642)
							(end 0.2794 0.1778)
						)
						(arc
							(start 0.2794 -0.1778)
							(mid 0.249642 -0.249642)
							(end 0.1778 -0.2794)
						)
					)
					(width 0)
					(fill yes)
				)
			)
		)
		(pad "2" smd custom
			(at 0 0.4445)
			(size 0.1397 0.1397)
			(layers "F.Cu" "F.Mask" "F.Paste")
			(net "GND")
			(options
				(clearance outline)
				(anchor circle)
			)
			(primitives
				(gr_poly
					(pts
						(arc
							(start -0.1778 -0.2794)
							(mid -0.249642 -0.249642)
							(end -0.2794 -0.1778)
						)
						(arc
							(start -0.2794 0.1778)
							(mid -0.249642 0.249642)
							(end -0.1778 0.2794)
						)
						(arc
							(start 0.1778 0.2794)
							(mid 0.249642 0.249642)
							(end 0.2794 0.1778)
						)
						(arc
							(start 0.2794 -0.1778)
							(mid 0.249642 -0.249642)
							(end 0.1778 -0.2794)
						)
					)
					(width 0)
					(fill yes)
				)
			)
		)
	)
	(footprint ""
		(layer "F.Cu")
		(at 149.932898 -62.270894)
		(property "Reference" "R773"
			(at 0 0 0)
			(layer "F.SilkS")
			(hide yes)
			(effects
				(font
					(size 1.27 1.27)
				)
			)
		)
		(property "Value" "2R6F-GP"
			(at -0.0508 -4.8514 0)
			(unlocked yes)
			(layer "F.Fab")
			(hide yes)
			(effects
				(font
					(size 1.016 1.016)
					(thickness 0.1524)
				)
			)
		)
		(property "Device Type" "R1206H26"
			(at 0 -6.3754 0)
			(unlocked yes)
			(layer "F.Fab")
			(hide yes)
			(effects
				(font
					(size 1.016 1.016)
					(thickness 0.1524)
				)
			)
		)
		(duplicate_pad_numbers_are_jumpers no)
		(fp_line
			(start -1.016 -2.2352)
			(end 1.016 -2.2352)
			(stroke
				(width 0.1524)
				(type default)
			)
			(layer "F.SilkS")
		)
		(fp_line
			(start -1.016 2.2352)
			(end -1.016 -2.2352)
			(stroke
				(width 0.1524)
				(type default)
			)
			(layer "F.SilkS")
		)
		(fp_line
			(start 1.016 -2.2352)
			(end 1.016 2.2352)
			(stroke
				(width 0.1524)
				(type default)
			)
			(layer "F.SilkS")
		)
		(fp_line
			(start 1.016 2.2352)
			(end -1.016 2.2352)
			(stroke
				(width 0.1524)
				(type default)
			)
			(layer "F.SilkS")
		)
		(fp_rect
			(start -1.0922 2.3114)
			(end 1.0922 -2.3114)
			(stroke
				(width 0)
				(type default)
			)
			(fill no)
			(layer "F.CrtYd")
		)
		(fp_poly
			(pts
				(xy -1.0922 -2.3114) (xy 1.0922 -2.3114) (xy 1.0922 2.3114) (xy -1.0922 2.3114)
			)
			(stroke
				(width 0)
				(type default)
			)
			(fill no)
			(layer "F.Fab")
		)
		(pad "1" smd rect
			(at 0 -1.397)
			(size 1.651 1.27)
			(layers "F.Cu" "F.Mask" "F.Paste")
			(net "P5V_HDD28")
		)
		(pad "2" smd rect
			(at 0 1.397)
			(size 1.651 1.27)
			(layers "F.Cu" "F.Mask" "F.Paste")
			(net "5V_PRE_28")
		)
	)
)
